(kicad_pcb
	(version 20260206)
	(generator "pcbnew")
	(generator_version "10.0")
	(general
		(thickness 1.6)
		(legacy_teardrops no)
	)
	(paper "A4")
	(title_block
		(title "v2-pdb — ms_pdb_v2.brd")
		(comment 1 "Open CloudServer (Microsoft) / footprint 331 of 348 (J9), pads 1-46 of 46")
	)
	(layers
		(0 "F.Cu" signal "TOP")
		(4 "In1.Cu" signal "GND")
		(6 "In2.Cu" signal "IN1")
		(8 "In3.Cu" signal "VCC")
		(10 "In4.Cu" signal "VCC1")
		(12 "In5.Cu" signal "IN2")
		(14 "In6.Cu" signal "GND1")
		(2 "B.Cu" signal "BOTTOM")
		(9 "F.Adhes" user "F.Adhesive")
		(11 "B.Adhes" user "B.Adhesive")
		(13 "F.Paste" user "Package Geometry/Pastemask Top")
		(15 "B.Paste" user "Package Geometry/Pastemask Bottom")
		(5 "F.SilkS" user "Ref Des/Silkscreen Top")
		(7 "B.SilkS" user "Ref Des/Silkscreen Bottom")
		(1 "F.Mask" user "Board Geometry/Soldermask Top")
		(3 "B.Mask" user "Board Geometry/Soldermask Bottom")
		(17 "Dwgs.User" user "User.Drawings")
		(19 "Cmts.User" user "User.Comments")
		(21 "Eco1.User" user "User.Eco1")
		(23 "Eco2.User" user "User.Eco2")
		(25 "Edge.Cuts" user "Board Geometry/Outline")
		(27 "Margin" user)
		(31 "F.CrtYd" user "Package Geometry/Place Bound Top")
		(29 "B.CrtYd" user "Package Geometry/Place Bound Bottom")
		(35 "F.Fab" user "Ref Des/Assembly Top")
		(33 "B.Fab" user "Ref Des/Assembly Bottom")
	)
	(footprint ""
		(layer "B.Cu")
		(at 44.03979 -97.16008 90)
		(property "Reference" "J9"
			(at 6.238748 -5.04063 0)
			(unlocked yes)
			(layer "B.SilkS")
			(effects
				(font
					(size 0.7874 0.5842)
					(thickness 0.1524)
				)
				(justify left mirror)
			)
		)
		(property "Value" ""
			(at 0 0 90)
			(layer "B.Fab")
			(effects
				(font
					(size 1.27 1.27)
				)
				(justify mirror)
			)
		)
		(duplicate_pad_numbers_are_jumpers no)
		(pad "" np_thru_hole circle
			(at -1.35001 -2.54)
			(size 2.5146 2.5146)
			(drill 2.5146)
			(layers "*.Cu" "*.Mask")
			(clearance 0.381)
			(thermal_gap 0.381)
		)
		(pad "" np_thru_hole circle
			(at 0 50.8)
			(size 2.5146 2.5146)
			(drill 2.5146)
			(layers "*.Cu" "*.Mask")
			(clearance 0.381)
			(thermal_gap 0.381)
		)
		(pad "P1" thru_hole rect
			(at 0 0)
			(size 1.1684 1.1684)
			(drill 0.762)
			(layers "*.Cu" "*.Mask")
			(remove_unused_layers no)
			(net "GND")
			(clearance 0.0508)
			(padstack
				(mode front_inner_back)
				(layer "Inner"
					(shape circle)
					(size 1.1684 1.1684)
					(clearance 0.0508)
				)
				(layer "B.Cu"
					(shape rect)
					(size 1.1684 1.1684)
					(thermal_gap 0.0508)
					(clearance 0.0508)
				)
			)
		)
		(pad "P2" thru_hole circle
			(at 0 2.54)
			(size 1.1684 1.1684)
			(drill 0.762)
			(layers "*.Cu" "*.Mask")
			(remove_unused_layers no)
			(net "GND")
			(clearance 0.0508)
			(thermal_gap 0.0508)
		)
		(pad "P3" thru_hole circle
			(at 0 5.08)
			(size 1.1684 1.1684)
			(drill 0.762)
			(layers "*.Cu" "*.Mask")
			(remove_unused_layers no)
			(net "GND")
			(clearance 0.0508)
			(thermal_gap 0.0508)
		)
		(pad "P4" thru_hole circle
			(at 0 7.62)
			(size 1.1684 1.1684)
			(drill 0.762)
			(layers "*.Cu" "*.Mask")
			(remove_unused_layers no)
			(net "GND")
			(clearance 0.0508)
			(thermal_gap 0.0508)
		)
		(pad "P5" thru_hole circle
			(at 0 10.16)
			(size 1.1684 1.1684)
			(drill 0.762)
			(layers "*.Cu" "*.Mask")
			(remove_unused_layers no)
			(net "GND")
			(clearance 0.0508)
			(thermal_gap 0.0508)
		)
		(pad "P6" thru_hole circle
			(at 0 12.7)
			(size 1.1684 1.1684)
			(drill 0.762)
			(layers "*.Cu" "*.Mask")
			(remove_unused_layers no)
			(net "GND")
			(clearance 0.0508)
			(thermal_gap 0.0508)
		)
		(pad "P7" thru_hole circle
			(at 0 15.24)
			(size 1.1684 1.1684)
			(drill 0.762)
			(layers "*.Cu" "*.Mask")
			(remove_unused_layers no)
			(net "GND")
			(clearance 0.0508)
			(thermal_gap 0.0508)
		)
		(pad "P8" thru_hole circle
			(at 0 17.78)
			(size 1.1684 1.1684)
			(drill 0.762)
			(layers "*.Cu" "*.Mask")
			(remove_unused_layers no)
			(net "GND")
			(clearance 0.0508)
			(thermal_gap 0.0508)
		)
		(pad "P9" thru_hole circle
			(at 0 20.32)
			(size 1.1684 1.1684)
			(drill 0.762)
			(layers "*.Cu" "*.Mask")
			(remove_unused_layers no)
			(net "P12V")
			(clearance 0.0508)
			(thermal_gap 0.0508)
		)
		(pad "P10" thru_hole circle
			(at 0 22.86)
			(size 1.1684 1.1684)
			(drill 0.762)
			(layers "*.Cu" "*.Mask")
			(remove_unused_layers no)
			(net "P12V")
			(clearance 0.0508)
			(thermal_gap 0.0508)
		)
		(pad "P11" thru_hole circle
			(at 0 25.4)
			(size 1.1684 1.1684)
			(drill 0.762)
			(layers "*.Cu" "*.Mask")
			(remove_unused_layers no)
			(net "P12V")
			(clearance 0.0508)
			(thermal_gap 0.0508)
		)
		(pad "P12" thru_hole circle
			(at 0 27.94)
			(size 1.1684 1.1684)
			(drill 0.762)
			(layers "*.Cu" "*.Mask")
			(remove_unused_layers no)
			(net "P12V")
			(clearance 0.0508)
			(thermal_gap 0.0508)
		)
		(pad "P13" thru_hole circle
			(at 0 30.48)
			(size 1.1684 1.1684)
			(drill 0.762)
			(layers "*.Cu" "*.Mask")
			(remove_unused_layers no)
			(net "P12V")
			(clearance 0.0508)
			(thermal_gap 0.0508)
		)
		(pad "P14" thru_hole circle
			(at 0 33.02)
			(size 1.1684 1.1684)
			(drill 0.762)
			(layers "*.Cu" "*.Mask")
			(remove_unused_layers no)
			(net "P12V")
			(clearance 0.0508)
			(thermal_gap 0.0508)
		)
		(pad "P15" thru_hole circle
			(at 0 35.56)
			(size 1.1684 1.1684)
			(drill 0.762)
			(layers "*.Cu" "*.Mask")
			(remove_unused_layers no)
			(net "P12V")
			(clearance 0.0508)
			(thermal_gap 0.0508)
		)
		(pad "P16" thru_hole circle
			(at 0 38.1)
			(size 1.1684 1.1684)
			(drill 0.762)
			(layers "*.Cu" "*.Mask")
			(remove_unused_layers no)
			(net "P12V")
			(clearance 0.0508)
			(thermal_gap 0.0508)
		)
		(pad "P17" thru_hole circle
			(at -2.70002 38.1)
			(size 1.1684 1.1684)
			(drill 0.762)
			(layers "*.Cu" "*.Mask")
			(remove_unused_layers no)
			(net "P12V")
			(clearance 0.0508)
			(thermal_gap 0.0508)
		)
		(pad "P18" thru_hole circle
			(at -2.70002 35.56)
			(size 1.1684 1.1684)
			(drill 0.762)
			(layers "*.Cu" "*.Mask")
			(remove_unused_layers no)
			(net "P12V")
			(clearance 0.0508)
			(thermal_gap 0.0508)
		)
		(pad "P19" thru_hole circle
			(at -2.70002 33.02)
			(size 1.1684 1.1684)
			(drill 0.762)
			(layers "*.Cu" "*.Mask")
			(remove_unused_layers no)
			(net "P12V")
			(clearance 0.0508)
			(thermal_gap 0.0508)
		)
		(pad "P20" thru_hole circle
			(at -2.70002 30.48)
			(size 1.1684 1.1684)
			(drill 0.762)
			(layers "*.Cu" "*.Mask")
			(remove_unused_layers no)
			(net "P12V")
			(clearance 0.0508)
			(thermal_gap 0.0508)
		)
		(pad "P21" thru_hole circle
			(at -2.70002 27.94)
			(size 1.1684 1.1684)
			(drill 0.762)
			(layers "*.Cu" "*.Mask")
			(remove_unused_layers no)
			(net "P12V")
			(clearance 0.0508)
			(thermal_gap 0.0508)
		)
		(pad "P22" thru_hole circle
			(at -2.70002 25.4)
			(size 1.1684 1.1684)
			(drill 0.762)
			(layers "*.Cu" "*.Mask")
			(remove_unused_layers no)
			(net "P12V")
			(clearance 0.0508)
			(thermal_gap 0.0508)
		)
		(pad "P23" thru_hole circle
			(at -2.70002 22.86)
			(size 1.1684 1.1684)
			(drill 0.762)
			(layers "*.Cu" "*.Mask")
			(remove_unused_layers no)
			(net "P12V")
			(clearance 0.0508)
			(thermal_gap 0.0508)
		)
		(pad "P24" thru_hole circle
			(at -2.70002 20.32)
			(size 1.1684 1.1684)
			(drill 0.762)
			(layers "*.Cu" "*.Mask")
			(remove_unused_layers no)
			(net "P12V")
			(clearance 0.0508)
			(thermal_gap 0.0508)
		)
		(pad "P25" thru_hole circle
			(at -2.70002 17.78)
			(size 1.1684 1.1684)
			(drill 0.762)
			(layers "*.Cu" "*.Mask")
			(remove_unused_layers no)
			(net "GND")
			(clearance 0.0508)
			(thermal_gap 0.0508)
		)
		(pad "P26" thru_hole circle
			(at -2.70002 15.24)
			(size 1.1684 1.1684)
			(drill 0.762)
			(layers "*.Cu" "*.Mask")
			(remove_unused_layers no)
			(net "GND")
			(clearance 0.0508)
			(thermal_gap 0.0508)
		)
		(pad "P27" thru_hole circle
			(at -2.70002 12.7)
			(size 1.1684 1.1684)
			(drill 0.762)
			(layers "*.Cu" "*.Mask")
			(remove_unused_layers no)
			(net "GND")
			(clearance 0.0508)
			(thermal_gap 0.0508)
		)
		(pad "P28" thru_hole circle
			(at -2.70002 10.16)
			(size 1.1684 1.1684)
			(drill 0.762)
			(layers "*.Cu" "*.Mask")
			(remove_unused_layers no)
			(net "GND")
			(clearance 0.0508)
			(thermal_gap 0.0508)
		)
		(pad "P29" thru_hole circle
			(at -2.70002 7.62)
			(size 1.1684 1.1684)
			(drill 0.762)
			(layers "*.Cu" "*.Mask")
			(remove_unused_layers no)
			(net "GND")
			(clearance 0.0508)
			(thermal_gap 0.0508)
		)
		(pad "P30" thru_hole circle
			(at -2.70002 5.08)
			(size 1.1684 1.1684)
			(drill 0.762)
			(layers "*.Cu" "*.Mask")
			(remove_unused_layers no)
			(net "GND")
			(clearance 0.0508)
			(thermal_gap 0.0508)
		)
		(pad "P31" thru_hole circle
			(at -2.70002 2.54)
			(size 1.1684 1.1684)
			(drill 0.762)
			(layers "*.Cu" "*.Mask")
			(remove_unused_layers no)
			(net "GND")
			(clearance 0.0508)
			(thermal_gap 0.0508)
		)
		(pad "P32" thru_hole circle
			(at -2.70002 0)
			(size 1.1684 1.1684)
			(drill 0.762)
			(layers "*.Cu" "*.Mask")
			(remove_unused_layers no)
			(net "GND")
			(clearance 0.0508)
			(thermal_gap 0.0508)
		)
		(pad "S1" thru_hole circle
			(at 0.55499 41.60012)
			(size 1.1684 1.1684)
			(drill 0.762)
			(layers "*.Cu" "*.Mask")
			(remove_unused_layers no)
			(net "T3_BLAD1_TXD")
			(clearance 0.0508)
			(thermal_gap 0.0508)
		)
		(pad "S2" thru_hole circle
			(at -0.71501 42.87012)
			(size 1.1684 1.1684)
			(drill 0.762)
			(layers "*.Cu" "*.Mask")
			(remove_unused_layers no)
			(net "T3_BLAD1_RXD")
			(clearance 0.0508)
			(thermal_gap 0.0508)
		)
		(pad "S3" thru_hole circle
			(at 0.55499 44.14012)
			(size 1.1684 1.1684)
			(drill 0.762)
			(layers "*.Cu" "*.Mask")
			(remove_unused_layers no)
			(net "T3_BLAD1_EN")
			(clearance 0.0508)
			(thermal_gap 0.0508)
		)
		(pad "S4" thru_hole circle
			(at -0.71501 45.41012)
			(size 1.1684 1.1684)
			(drill 0.762)
			(layers "*.Cu" "*.Mask")
			(remove_unused_layers no)
			(net "B5_PSU_ALERT_N")
			(clearance 0.0508)
			(thermal_gap 0.0508)
		)
		(pad "S5" thru_hole circle
			(at 0.55499 46.68012)
			(size 1.1684 1.1684)
			(drill 0.762)
			(layers "*.Cu" "*.Mask")
			(remove_unused_layers no)
			(net "T3_BLAD2_TXD")
			(clearance 0.0508)
			(thermal_gap 0.0508)
		)
		(pad "S6" thru_hole circle
			(at -0.71501 47.95012)
			(size 1.1684 1.1684)
			(drill 0.762)
			(layers "*.Cu" "*.Mask")
			(remove_unused_layers no)
			(net "T3_BLAD2_RXD")
			(clearance 0.0508)
			(thermal_gap 0.0508)
		)
		(pad "S7" thru_hole circle
			(at -3.25501 47.95012)
			(size 1.1684 1.1684)
			(drill 0.762)
			(layers "*.Cu" "*.Mask")
			(remove_unused_layers no)
			(net "T3_BLAD4_RXD")
			(clearance 0.0508)
			(thermal_gap 0.0508)
		)
		(pad "S8" thru_hole circle
			(at -1.98501 46.68012)
			(size 1.1684 1.1684)
			(drill 0.762)
			(layers "*.Cu" "*.Mask")
			(remove_unused_layers no)
			(net "T3_BLAD4_TXD")
			(clearance 0.0508)
			(thermal_gap 0.0508)
		)
		(pad "S9" thru_hole circle
			(at -3.25501 45.41012)
			(size 1.1684 1.1684)
			(drill 0.762)
			(layers "*.Cu" "*.Mask")
			(remove_unused_layers no)
			(net "B6_PSU_ALERT_N")
			(clearance 0.0508)
			(thermal_gap 0.0508)
		)
		(pad "S10" thru_hole circle
			(at -1.98501 44.14012)
			(size 1.1684 1.1684)
			(drill 0.762)
			(layers "*.Cu" "*.Mask")
			(remove_unused_layers no)
			(net "T3_BLAD3_EN")
			(clearance 0.0508)
			(thermal_gap 0.0508)
		)
		(pad "S11" thru_hole circle
			(at -3.25501 42.87012)
			(size 1.1684 1.1684)
			(drill 0.762)
			(layers "*.Cu" "*.Mask")
			(remove_unused_layers no)
			(net "T3_BLAD3_RXD")
			(clearance 0.0508)
			(thermal_gap 0.0508)
		)
		(pad "S12" thru_hole circle
			(at -1.98501 41.60012)
			(size 1.1684 1.1684)
			(drill 0.762)
			(layers "*.Cu" "*.Mask")
			(remove_unused_layers no)
			(net "T3_BLAD3_TXD")
			(clearance 0.0508)
			(thermal_gap 0.0508)
		)
	)
)
